(kicad_pcb
	(version 20260206)
	(generator "pcbnew")
	(generator_version "10.0")
	(general
		(thickness 1.6)
		(legacy_teardrops no)
	)
	(paper "A4")
	(title_block
		(title "03242023_DA0F0TMBIJ0_F0T_Motherboard_J_brd_V01_OCP.brd")
		(comment 1 "Grand Teton / footprints 5028-5033 of 6105")
	)
	(layers
		(0 "F.Cu" signal "TOP")
		(4 "In1.Cu" signal "GND")
		(6 "In2.Cu" signal "IN1")
		(8 "In3.Cu" signal "GND1")
		(10 "In4.Cu" signal "IN2")
		(12 "In5.Cu" signal "GND2")
		(14 "In6.Cu" signal "IN3")
		(16 "In7.Cu" signal "GND3")
		(18 "In8.Cu" signal "VCC")
		(20 "In9.Cu" signal "VCC1")
		(22 "In10.Cu" signal "GND4")
		(24 "In11.Cu" signal "IN4")
		(26 "In12.Cu" signal "GND5")
		(28 "In13.Cu" signal "IN5")
		(30 "In14.Cu" signal "GND6")
		(32 "In15.Cu" signal "IN6")
		(34 "In16.Cu" signal "GND7")
		(2 "B.Cu" signal "BOTTOM")
		(9 "F.Adhes" user "F.Adhesive")
		(11 "B.Adhes" user "B.Adhesive")
		(13 "F.Paste" user "Package Geometry/Pastemask Top")
		(15 "B.Paste" user "Package Geometry/Pastemask Bottom")
		(5 "F.SilkS" user "Ref Des/Silkscreen Top")
		(7 "B.SilkS" user "Ref Des/Silkscreen Bottom")
		(1 "F.Mask" user "Board Geometry/Soldermask Top")
		(3 "B.Mask" user "Board Geometry/Soldermask Bottom")
		(17 "Dwgs.User" user "User.Drawings")
		(19 "Cmts.User" user "User.Comments")
		(21 "Eco1.User" user "User.Eco1")
		(23 "Eco2.User" user "User.Eco2")
		(25 "Edge.Cuts" user "Board Geometry/Outline")
		(27 "Margin" user)
		(31 "F.CrtYd" user "Package Geometry/Place Bound Top")
		(29 "B.CrtYd" user "Package Geometry/Place Bound Bottom")
		(35 "F.Fab" user "Ref Des/Assembly Top")
		(33 "B.Fab" user "Ref Des/Assembly Bottom")
	)
	(footprint ""
		(layer "B.Cu")
		(at 245.835424 -99.136708)
		(property "Reference" "R953"
			(at 0 0 0)
			(layer "B.SilkS")
			(hide yes)
			(effects
				(font
					(size 1.27 1.27)
				)
				(justify mirror)
			)
		)
		(property "Value" ""
			(at 0 0 0)
			(layer "B.Fab")
			(effects
				(font
					(size 1.27 1.27)
				)
				(justify mirror)
			)
		)
		(duplicate_pad_numbers_are_jumpers no)
		(fp_line
			(start -0.7874 -0.4064)
			(end -0.7874 0.4064)
			(stroke
				(width 0.1524)
				(type default)
			)
			(layer "B.SilkS")
		)
		(fp_line
			(start -0.7874 0.4064)
			(end 0.7874 0.4064)
			(stroke
				(width 0.1524)
				(type default)
			)
			(layer "B.SilkS")
		)
		(fp_line
			(start 0.7874 -0.4064)
			(end -0.7874 -0.4064)
			(stroke
				(width 0.1524)
				(type default)
			)
			(layer "B.SilkS")
		)
		(fp_line
			(start 0.7874 0.4064)
			(end 0.7874 -0.4064)
			(stroke
				(width 0.1524)
				(type default)
			)
			(layer "B.SilkS")
		)
		(fp_line
			(start -0.67945 -0.3048)
			(end -0.67945 0.3048)
			(stroke
				(width 0.1)
				(type default)
			)
			(layer "B.Fab")
		)
		(fp_line
			(start -0.67945 0.3048)
			(end -0.120396 0.3048)
			(stroke
				(width 0.1)
				(type default)
			)
			(layer "B.Fab")
		)
		(fp_line
			(start -0.12065 -0.3048)
			(end -0.67945 -0.3048)
			(stroke
				(width 0.1)
				(type default)
			)
			(layer "B.Fab")
		)
		(fp_line
			(start -0.12065 -0.2794)
			(end -0.12065 -0.3048)
			(stroke
				(width 0.1)
				(type default)
			)
			(layer "B.Fab")
		)
		(fp_line
			(start -0.120396 0.2794)
			(end 0.12065 0.2794)
			(stroke
				(width 0.1)
				(type default)
			)
			(layer "B.Fab")
		)
		(fp_line
			(start -0.120396 0.3048)
			(end -0.120396 0.2794)
			(stroke
				(width 0.1)
				(type default)
			)
			(layer "B.Fab")
		)
		(fp_line
			(start 0.12065 -0.305054)
			(end 0.12065 -0.2794)
			(stroke
				(width 0.1)
				(type default)
			)
			(layer "B.Fab")
		)
		(fp_line
			(start 0.12065 -0.2794)
			(end -0.12065 -0.2794)
			(stroke
				(width 0.1)
				(type default)
			)
			(layer "B.Fab")
		)
		(fp_line
			(start 0.12065 0.2794)
			(end 0.12065 0.3048)
			(stroke
				(width 0.1)
				(type default)
			)
			(layer "B.Fab")
		)
		(fp_line
			(start 0.12065 0.3048)
			(end 0.67945 0.3048)
			(stroke
				(width 0.1)
				(type default)
			)
			(layer "B.Fab")
		)
		(fp_line
			(start 0.67945 -0.305054)
			(end 0.12065 -0.305054)
			(stroke
				(width 0.1)
				(type default)
			)
			(layer "B.Fab")
		)
		(fp_line
			(start 0.67945 0.3048)
			(end 0.67945 -0.305054)
			(stroke
				(width 0.1)
				(type default)
			)
			(layer "B.Fab")
		)
		(pad "1" smd circle
			(at 0.40005 0 180)
			(size 0 0)
			(layers "B.Cu" "B.Mask" "B.Paste")
			(net "CLK_CK440_SMB_ADDR0")
		)
		(pad "2" smd circle
			(at -0.40005 0 180)
			(size 0 0)
			(layers "B.Cu" "B.Mask" "B.Paste")
			(net "GND")
		)
	)
	(footprint ""
		(layer "B.Cu")
		(at 302.218852 -53.018182 180)
		(property "Reference" "C1178"
			(at 0 0 0)
			(layer "B.SilkS")
			(hide yes)
			(effects
				(font
					(size 1.27 1.27)
				)
				(justify mirror)
			)
		)
		(property "Value" ""
			(at 0 0 0)
			(layer "B.Fab")
			(effects
				(font
					(size 1.27 1.27)
				)
				(justify mirror)
			)
		)
		(duplicate_pad_numbers_are_jumpers no)
		(fp_line
			(start 1.2954 0.5842)
			(end 1.2954 -0.5842)
			(stroke
				(width 0.1524)
				(type default)
			)
			(layer "B.SilkS")
		)
		(fp_line
			(start 1.2954 -0.5842)
			(end -1.2954 -0.5842)
			(stroke
				(width 0.1524)
				(type default)
			)
			(layer "B.SilkS")
		)
		(fp_line
			(start 0 -0.5842)
			(end 0 0.5842)
			(stroke
				(width 0.1524)
				(type default)
			)
			(layer "B.SilkS")
		)
		(fp_line
			(start -1.2954 0.5842)
			(end 1.2954 0.5842)
			(stroke
				(width 0.1524)
				(type default)
			)
			(layer "B.SilkS")
		)
		(fp_line
			(start -1.2954 -0.5842)
			(end -1.2954 0.5842)
			(stroke
				(width 0.1524)
				(type default)
			)
			(layer "B.SilkS")
		)
		(fp_line
			(start 1.1938 0.4064)
			(end 1.1938 -0.4064)
			(stroke
				(width 0.1)
				(type default)
			)
			(layer "B.Fab")
		)
		(fp_line
			(start 1.1938 -0.4064)
			(end 0.8636 -0.4064)
			(stroke
				(width 0.1)
				(type default)
			)
			(layer "B.Fab")
		)
		(fp_line
			(start 0.8636 0.4572)
			(end 0.8636 0.4064)
			(stroke
				(width 0.1)
				(type default)
			)
			(layer "B.Fab")
		)
		(fp_line
			(start 0.8636 0.4064)
			(end 1.1938 0.4064)
			(stroke
				(width 0.1)
				(type default)
			)
			(layer "B.Fab")
		)
		(fp_line
			(start 0.8636 -0.4064)
			(end 0.8636 -0.4572)
			(stroke
				(width 0.1)
				(type default)
			)
			(layer "B.Fab")
		)
		(fp_line
			(start 0.8636 -0.4572)
			(end -0.8636 -0.4572)
			(stroke
				(width 0.1)
				(type default)
			)
			(layer "B.Fab")
		)
		(fp_line
			(start -0.8636 0.4572)
			(end 0.8636 0.4572)
			(stroke
				(width 0.1)
				(type default)
			)
			(layer "B.Fab")
		)
		(fp_line
			(start -0.8636 0.4064)
			(end -0.8636 0.4572)
			(stroke
				(width 0.1)
				(type default)
			)
			(layer "B.Fab")
		)
		(fp_line
			(start -0.8636 -0.4064)
			(end -1.1938 -0.4064)
			(stroke
				(width 0.1)
				(type default)
			)
			(layer "B.Fab")
		)
		(fp_line
			(start -0.8636 -0.4572)
			(end -0.8636 -0.4064)
			(stroke
				(width 0.1)
				(type default)
			)
			(layer "B.Fab")
		)
		(fp_line
			(start -1.1938 0.4064)
			(end -0.8636 0.4064)
			(stroke
				(width 0.1)
				(type default)
			)
			(layer "B.Fab")
		)
		(fp_line
			(start -1.1938 -0.4064)
			(end -1.1938 0.4064)
			(stroke
				(width 0.1)
				(type default)
			)
			(layer "B.Fab")
		)
		(pad "1" smd rect
			(at 0.7366 0 90)
			(size 0.7112 0.8128)
			(layers "B.Cu" "B.Mask" "B.Paste")
			(net "P1V05_PCH_AUX")
		)
		(pad "2" smd rect
			(at -0.7366 0 90)
			(size 0.7112 0.8128)
			(layers "B.Cu" "B.Mask" "B.Paste")
			(net "GND")
		)
	)
	(footprint ""
		(layer "B.Cu")
		(at 106.281474 -359.47985 180)
		(property "Reference" "C2860"
			(at 0 0 0)
			(layer "B.SilkS")
			(hide yes)
			(effects
				(font
					(size 1.27 1.27)
				)
				(justify mirror)
			)
		)
		(property "Value" ""
			(at 0 0 0)
			(layer "B.Fab")
			(effects
				(font
					(size 1.27 1.27)
				)
				(justify mirror)
			)
		)
		(duplicate_pad_numbers_are_jumpers no)
		(fp_line
			(start 0.7874 0.4064)
			(end 0.7874 -0.4064)
			(stroke
				(width 0.1524)
				(type default)
			)
			(layer "B.SilkS")
		)
		(fp_line
			(start 0.7874 -0.4064)
			(end -0.7874 -0.4064)
			(stroke
				(width 0.1524)
				(type default)
			)
			(layer "B.SilkS")
		)
		(fp_line
			(start -0.7874 0.4064)
			(end 0.7874 0.4064)
			(stroke
				(width 0.1524)
				(type default)
			)
			(layer "B.SilkS")
		)
		(fp_line
			(start -0.7874 -0.4064)
			(end -0.7874 0.4064)
			(stroke
				(width 0.1524)
				(type default)
			)
			(layer "B.SilkS")
		)
		(fp_line
			(start 0.67945 0.3048)
			(end 0.67945 -0.305054)
			(stroke
				(width 0.1)
				(type default)
			)
			(layer "B.Fab")
		)
		(fp_line
			(start 0.67945 -0.305054)
			(end 0.12065 -0.305054)
			(stroke
				(width 0.1)
				(type default)
			)
			(layer "B.Fab")
		)
		(fp_line
			(start 0.12065 0.3048)
			(end 0.67945 0.3048)
			(stroke
				(width 0.1)
				(type default)
			)
			(layer "B.Fab")
		)
		(fp_line
			(start 0.12065 0.2794)
			(end 0.12065 0.3048)
			(stroke
				(width 0.1)
				(type default)
			)
			(layer "B.Fab")
		)
		(fp_line
			(start 0.12065 -0.2794)
			(end -0.12065 -0.2794)
			(stroke
				(width 0.1)
				(type default)
			)
			(layer "B.Fab")
		)
		(fp_line
			(start 0.12065 -0.305054)
			(end 0.12065 -0.2794)
			(stroke
				(width 0.1)
				(type default)
			)
			(layer "B.Fab")
		)
		(fp_line
			(start -0.120396 0.3048)
			(end -0.120396 0.2794)
			(stroke
				(width 0.1)
				(type default)
			)
			(layer "B.Fab")
		)
		(fp_line
			(start -0.120396 0.2794)
			(end 0.12065 0.2794)
			(stroke
				(width 0.1)
				(type default)
			)
			(layer "B.Fab")
		)
		(fp_line
			(start -0.12065 -0.2794)
			(end -0.12065 -0.3048)
			(stroke
				(width 0.1)
				(type default)
			)
			(layer "B.Fab")
		)
		(fp_line
			(start -0.12065 -0.3048)
			(end -0.67945 -0.3048)
			(stroke
				(width 0.1)
				(type default)
			)
			(layer "B.Fab")
		)
		(fp_line
			(start -0.67945 0.3048)
			(end -0.120396 0.3048)
			(stroke
				(width 0.1)
				(type default)
			)
			(layer "B.Fab")
		)
		(fp_line
			(start -0.67945 -0.3048)
			(end -0.67945 0.3048)
			(stroke
				(width 0.1)
				(type default)
			)
			(layer "B.Fab")
		)
		(pad "1" smd circle
			(at 0.40005 0)
			(size 0 0)
			(layers "B.Cu" "B.Mask" "B.Paste")
			(net "PVCCIN_CPU1_EN_R")
		)
		(pad "2" smd circle
			(at -0.40005 0)
			(size 0 0)
			(layers "B.Cu" "B.Mask" "B.Paste")
			(net "GND")
		)
	)
	(footprint ""
		(layer "B.Cu")
		(at 514.718808 2.286 90)
		(property "Reference" "X17"
			(at 1.35128 3.208782 270)
			(unlocked yes)
			(layer "B.SilkS")
			(effects
				(font
					(size 0.7874 0.5842)
					(thickness 0.1524)
				)
				(justify left mirror)
			)
		)
		(property "Value" ""
			(at 0 0 90)
			(layer "B.Fab")
			(effects
				(font
					(size 1.27 1.27)
				)
				(justify mirror)
			)
		)
		(property "Device Type" "TP_TDR_4P_FTS_TH-TP_TDR_4P_DIPA"
			(at -1.30175 1.27 0)
			(unlocked yes)
			(layer "B.Fab")
			(hide yes)
			(effects
				(font
					(size 0.635 0.4064)
					(thickness 0.1524)
				)
				(justify mirror)
			)
		)
		(property "User Part Number" "N_A"
			(at -1.30175 1.27 0)
			(unlocked yes)
			(layer "Cmts.User")
			(hide yes)
			(effects
				(font
					(size 0.635 0.4064)
					(thickness 0.1524)
				)
				(justify mirror)
			)
		)
		(duplicate_pad_numbers_are_jumpers no)
		(fp_line
			(start 0 -1.27)
			(end 0 -0.635)
			(stroke
				(width 0.1524)
				(type default)
			)
			(layer "B.SilkS")
		)
		(fp_line
			(start -2.54 -1.27)
			(end 0 -1.27)
			(stroke
				(width 0.1524)
				(type default)
			)
			(layer "B.SilkS")
		)
		(fp_line
			(start -2.54 -1.1303)
			(end -2.54 -1.27)
			(stroke
				(width 0.1524)
				(type default)
			)
			(layer "B.SilkS")
		)
		(fp_line
			(start 0 0.635)
			(end 0 1.905)
			(stroke
				(width 0.1524)
				(type default)
			)
			(layer "B.SilkS")
		)
		(fp_line
			(start -2.54 1.4097)
			(end -2.54 1.1303)
			(stroke
				(width 0.1524)
				(type default)
			)
			(layer "B.SilkS")
		)
		(fp_line
			(start 0 3.175)
			(end 0 3.81)
			(stroke
				(width 0.1524)
				(type default)
			)
			(layer "B.SilkS")
		)
		(fp_line
			(start 0 3.81)
			(end -2.54 3.81)
			(stroke
				(width 0.1524)
				(type default)
			)
			(layer "B.SilkS")
		)
		(fp_line
			(start -2.54 3.81)
			(end -2.54 3.6703)
			(stroke
				(width 0.1524)
				(type default)
			)
			(layer "B.SilkS")
		)
		(fp_poly
			(pts
				(xy 2.285746 -0.762) (xy 2.285746 0.762) (xy 0.761746 0)
			)
			(stroke
				(width 0)
				(type default)
			)
			(fill yes)
			(layer "B.SilkS")
		)
		(fp_line
			(start 0 -1.27)
			(end 0 3.81)
			(stroke
				(width 0.1)
				(type default)
			)
			(layer "B.Fab")
		)
		(fp_line
			(start -2.54 -1.27)
			(end 0 -1.27)
			(stroke
				(width 0.1)
				(type default)
			)
			(layer "B.Fab")
		)
		(fp_line
			(start 0 3.81)
			(end -2.54 3.81)
			(stroke
				(width 0.1)
				(type default)
			)
			(layer "B.Fab")
		)
		(fp_line
			(start -2.54 3.81)
			(end -2.54 -1.27)
			(stroke
				(width 0.1)
				(type default)
			)
			(layer "B.Fab")
		)
		(fp_poly
			(pts
				(xy 0.761746 0) (xy 2.285746 -0.762) (xy 2.285746 0.762)
			)
			(stroke
				(width 0)
				(type default)
			)
			(fill yes)
			(layer "B.Fab")
		)
		(pad "1" thru_hole circle
			(at 0 0 270)
			(size 1.0033 1.0033)
			(drill 0.249936)
			(layers "*.Cu" "*.Mask")
			(remove_unused_layers no)
			(net "TDR_DIFF_100_IN4_DP")
			(clearance 0.10795)
			(padstack
				(mode front_inner_back)
				(layer "Inner"
					(shape circle)
					(size 0.8001 0.8001)
					(clearance 0.1524)
				)
				(layer "B.Cu"
					(shape circle)
					(size 1.0033 1.0033)
					(thermal_gap 0.10795)
					(clearance 0.10795)
				)
			)
		)
		(pad "2" thru_hole circle
			(at -2.54 0 270)
			(size 1.9939 1.9939)
			(drill 0.249936)
			(layers "*.Cu" "*.Mask")
			(remove_unused_layers no)
			(net "T1_GND")
			(clearance 0.10795)
			(padstack
				(mode front_inner_back)
				(layer "Inner"
					(shape circle)
					(size 0.8001 0.8001)
					(clearance 0.1524)
				)
				(layer "B.Cu"
					(shape circle)
					(size 1.9939 1.9939)
					(thermal_gap 0.10795)
					(clearance 0.10795)
				)
			)
		)
		(pad "3" thru_hole circle
			(at -2.54 2.54 270)
			(size 1.9939 1.9939)
			(drill 0.249936)
			(layers "*.Cu" "*.Mask")
			(remove_unused_layers no)
			(net "T1_GND")
			(clearance 0.10795)
			(padstack
				(mode front_inner_back)
				(layer "Inner"
					(shape circle)
					(size 0.8001 0.8001)
					(clearance 0.1524)
				)
				(layer "B.Cu"
					(shape circle)
					(size 1.9939 1.9939)
					(thermal_gap 0.10795)
					(clearance 0.10795)
				)
			)
		)
		(pad "4" thru_hole circle
			(at 0 2.54 270)
			(size 1.0033 1.0033)
			(drill 0.249936)
			(layers "*.Cu" "*.Mask")
			(remove_unused_layers no)
			(net "TDR_DIFF_100_IN4_DN")
			(clearance 0.10795)
			(padstack
				(mode front_inner_back)
				(layer "Inner"
					(shape circle)
					(size 0.8001 0.8001)
					(clearance 0.1524)
				)
				(layer "B.Cu"
					(shape circle)
					(size 1.0033 1.0033)
					(thermal_gap 0.10795)
					(clearance 0.10795)
				)
			)
		)
	)
	(footprint ""
		(layer "B.Cu")
		(at 369.485418 -296.054526 180)
		(property "Reference" "C398"
			(at 0 0 0)
			(layer "B.SilkS")
			(hide yes)
			(effects
				(font
					(size 1.27 1.27)
				)
				(justify mirror)
			)
		)
		(property "Value" ""
			(at 0 0 0)
			(layer "B.Fab")
			(effects
				(font
					(size 1.27 1.27)
				)
				(justify mirror)
			)
		)
		(duplicate_pad_numbers_are_jumpers no)
		(fp_line
			(start 1.524 0.762)
			(end 1.524 -0.762)
			(stroke
				(width 0.1524)
				(type default)
			)
			(layer "B.SilkS")
		)
		(fp_line
			(start 1.524 -0.762)
			(end -1.524 -0.762)
			(stroke
				(width 0.1524)
				(type default)
			)
			(layer "B.SilkS")
		)
		(fp_line
			(start -1.524 0.762)
			(end 1.524 0.762)
			(stroke
				(width 0.1524)
				(type default)
			)
			(layer "B.SilkS")
		)
		(fp_line
			(start -1.524 -0.762)
			(end -1.524 0.762)
			(stroke
				(width 0.1524)
				(type default)
			)
			(layer "B.SilkS")
		)
		(fp_line
			(start 1.1049 0.724916)
			(end -1.1049 0.724916)
			(stroke
				(width 0.1)
				(type default)
			)
			(layer "B.Fab")
		)
		(fp_line
			(start 1.1049 -0.724916)
			(end 1.1049 0.724916)
			(stroke
				(width 0.1)
				(type default)
			)
			(layer "B.Fab")
		)
		(fp_line
			(start -1.1049 0.724916)
			(end -1.1049 -0.724916)
			(stroke
				(width 0.1)
				(type default)
			)
			(layer "B.Fab")
		)
		(fp_line
			(start -1.1049 -0.724916)
			(end 1.1049 -0.724916)
			(stroke
				(width 0.1)
				(type default)
			)
			(layer "B.Fab")
		)
		(pad "1" smd rect
			(at 0.889 0 180)
			(size 1.016 1.27)
			(layers "B.Cu" "B.Mask" "B.Paste")
			(net "PVCCIN_CPU0")
		)
		(pad "2" smd rect
			(at -0.889 0 180)
			(size 1.016 1.27)
			(layers "B.Cu" "B.Mask" "B.Paste")
			(net "GND")
		)
	)
	(footprint ""
		(layer "B.Cu")
		(at 312.443622 -34.102548 180)
		(property "Reference" "R494"
			(at 0 0 0)
			(layer "B.SilkS")
			(hide yes)
			(effects
				(font
					(size 1.27 1.27)
				)
				(justify mirror)
			)
		)
		(property "Value" ""
			(at 0 0 0)
			(layer "B.Fab")
			(effects
				(font
					(size 1.27 1.27)
				)
				(justify mirror)
			)
		)
		(duplicate_pad_numbers_are_jumpers no)
		(fp_line
			(start 0.7874 0.4064)
			(end 0.7874 -0.4064)
			(stroke
				(width 0.1524)
				(type default)
			)
			(layer "B.SilkS")
		)
		(fp_line
			(start 0.7874 -0.4064)
			(end -0.7874 -0.4064)
			(stroke
				(width 0.1524)
				(type default)
			)
			(layer "B.SilkS")
		)
		(fp_line
			(start -0.7874 0.4064)
			(end 0.7874 0.4064)
			(stroke
				(width 0.1524)
				(type default)
			)
			(layer "B.SilkS")
		)
		(fp_line
			(start -0.7874 -0.4064)
			(end -0.7874 0.4064)
			(stroke
				(width 0.1524)
				(type default)
			)
			(layer "B.SilkS")
		)
		(fp_line
			(start 0.67945 0.3048)
			(end 0.67945 -0.305054)
			(stroke
				(width 0.1)
				(type default)
			)
			(layer "B.Fab")
		)
		(fp_line
			(start 0.67945 -0.305054)
			(end 0.12065 -0.305054)
			(stroke
				(width 0.1)
				(type default)
			)
			(layer "B.Fab")
		)
		(fp_line
			(start 0.12065 0.3048)
			(end 0.67945 0.3048)
			(stroke
				(width 0.1)
				(type default)
			)
			(layer "B.Fab")
		)
		(fp_line
			(start 0.12065 0.2794)
			(end 0.12065 0.3048)
			(stroke
				(width 0.1)
				(type default)
			)
			(layer "B.Fab")
		)
		(fp_line
			(start 0.12065 -0.2794)
			(end -0.12065 -0.2794)
			(stroke
				(width 0.1)
				(type default)
			)
			(layer "B.Fab")
		)
		(fp_line
			(start 0.12065 -0.305054)
			(end 0.12065 -0.2794)
			(stroke
				(width 0.1)
				(type default)
			)
			(layer "B.Fab")
		)
		(fp_line
			(start -0.120396 0.3048)
			(end -0.120396 0.2794)
			(stroke
				(width 0.1)
				(type default)
			)
			(layer "B.Fab")
		)
		(fp_line
			(start -0.120396 0.2794)
			(end 0.12065 0.2794)
			(stroke
				(width 0.1)
				(type default)
			)
			(layer "B.Fab")
		)
		(fp_line
			(start -0.12065 -0.2794)
			(end -0.12065 -0.3048)
			(stroke
				(width 0.1)
				(type default)
			)
			(layer "B.Fab")
		)
		(fp_line
			(start -0.12065 -0.3048)
			(end -0.67945 -0.3048)
			(stroke
				(width 0.1)
				(type default)
			)
			(layer "B.Fab")
		)
		(fp_line
			(start -0.67945 0.3048)
			(end -0.120396 0.3048)
			(stroke
				(width 0.1)
				(type default)
			)
			(layer "B.Fab")
		)
		(fp_line
			(start -0.67945 -0.3048)
			(end -0.67945 0.3048)
			(stroke
				(width 0.1)
				(type default)
			)
			(layer "B.Fab")
		)
		(pad "1" smd circle
			(at 0.40005 0)
			(size 0 0)
			(layers "B.Cu" "B.Mask" "B.Paste")
			(net "P3V3_AUX")
		)
		(pad "2" smd circle
			(at -0.40005 0)
			(size 0 0)
			(layers "B.Cu" "B.Mask" "B.Paste")
			(net "IRQ_LVC3_WAKE_N")
		)
	)
)
